(kicad_pcb
	(version 20260206)
	(generator "pcbnew")
	(generator_version "10.0")
	(general
		(thickness 1.6)
		(legacy_teardrops no)
	)
	(paper "A4")
	(title_block
		(title "Bryce Canyon_F.DPB_16315-1-OCP.brd")
		(comment 1 "Bryce Canyon / footprints 829-835 of 2223")
	)
	(layers
		(0 "F.Cu" signal "TOP")
		(4 "In1.Cu" signal "L2GND")
		(6 "In2.Cu" signal "L3")
		(8 "In3.Cu" signal "L4GND")
		(10 "In4.Cu" signal "L5")
		(12 "In5.Cu" signal "L6VCC")
		(14 "In6.Cu" signal "L7VCC")
		(16 "In7.Cu" signal "L8")
		(18 "In8.Cu" signal "L9GND")
		(20 "In9.Cu" signal "L10")
		(22 "In10.Cu" signal "L11GND")
		(2 "B.Cu" signal "BOTTOM")
		(9 "F.Adhes" user "F.Adhesive")
		(11 "B.Adhes" user "B.Adhesive")
		(13 "F.Paste" user "Package Geometry/Pastemask Top")
		(15 "B.Paste" user "Package Geometry/Pastemask Bottom")
		(5 "F.SilkS" user "Ref Des/Silkscreen Top")
		(7 "B.SilkS" user "Ref Des/Silkscreen Bottom")
		(1 "F.Mask" user "Board Geometry/Soldermask Top")
		(3 "B.Mask" user "Board Geometry/Soldermask Bottom")
		(17 "Dwgs.User" user "User.Drawings")
		(19 "Cmts.User" user "User.Comments")
		(21 "Eco1.User" user "User.Eco1")
		(23 "Eco2.User" user "User.Eco2")
		(25 "Edge.Cuts" user "Board Geometry/Outline")
		(27 "Margin" user)
		(31 "F.CrtYd" user "Package Geometry/Place Bound Top")
		(29 "B.CrtYd" user "Package Geometry/Place Bound Bottom")
		(35 "F.Fab" user "Ref Des/Assembly Top")
		(33 "B.Fab" user "Ref Des/Assembly Bottom")
	)
	(footprint ""
		(layer "F.Cu")
		(at 441.964826 -127.254)
		(property "Reference" "R342"
			(at 0 0 0)
			(layer "F.SilkS")
			(hide yes)
			(effects
				(font
					(size 1.27 1.27)
				)
			)
		)
		(property "Value" "91R3F-1-GP"
			(at -0.0254 -2.5146 0)
			(unlocked yes)
			(layer "F.Fab")
			(hide yes)
			(effects
				(font
					(size 1.016 1.016)
					(thickness 0.1524)
				)
			)
		)
		(property "Device Type" "R603H22"
			(at -0.0254 -4.0386 0)
			(unlocked yes)
			(layer "F.Fab")
			(hide yes)
			(effects
				(font
					(size 1.016 1.016)
					(thickness 0.1524)
				)
			)
		)
		(duplicate_pad_numbers_are_jumpers no)
		(fp_line
			(start -0.4826 0)
			(end -0.2032 0)
			(stroke
				(width 0.2032)
				(type default)
			)
			(layer "F.SilkS")
		)
		(fp_line
			(start 0.2032 0)
			(end 0.4826 0)
			(stroke
				(width 0.2032)
				(type default)
			)
			(layer "F.SilkS")
		)
		(fp_rect
			(start -0.5842 1.3335)
			(end 0.5842 -1.3335)
			(stroke
				(width 0)
				(type default)
			)
			(fill no)
			(layer "F.CrtYd")
		)
		(fp_rect
			(start -0.5842 1.3335)
			(end 0.5842 -1.3335)
			(stroke
				(width 0)
				(type default)
			)
			(fill no)
			(layer "F.Fab")
		)
		(pad "1" smd custom
			(at 0 -0.762)
			(size 0.2159 0.2159)
			(layers "F.Cu" "F.Mask" "F.Paste")
			(net "P5V_A_4")
			(options
				(clearance outline)
				(anchor circle)
			)
			(primitives
				(gr_poly
					(pts
						(arc
							(start -0.3302 -0.4318)
							(mid -0.402042 -0.402042)
							(end -0.4318 -0.3302)
						)
						(arc
							(start -0.4318 0.3302)
							(mid -0.402042 0.402042)
							(end -0.3302 0.4318)
						)
						(arc
							(start 0.3302 0.4318)
							(mid 0.402042 0.402042)
							(end 0.4318 0.3302)
						)
						(arc
							(start 0.4318 -0.3302)
							(mid 0.402042 -0.402042)
							(end 0.3302 -0.4318)
						)
					)
					(width 0)
					(fill yes)
				)
			)
		)
		(pad "2" smd custom
			(at 0 0.762)
			(size 0.2159 0.2159)
			(layers "F.Cu" "F.Mask" "F.Paste")
			(net "DRV_ACT_22")
			(options
				(clearance outline)
				(anchor circle)
			)
			(primitives
				(gr_poly
					(pts
						(arc
							(start -0.3302 -0.4318)
							(mid -0.402042 -0.402042)
							(end -0.4318 -0.3302)
						)
						(arc
							(start -0.4318 0.3302)
							(mid -0.402042 0.402042)
							(end -0.3302 0.4318)
						)
						(arc
							(start 0.3302 0.4318)
							(mid 0.402042 0.402042)
							(end 0.4318 0.3302)
						)
						(arc
							(start 0.4318 -0.3302)
							(mid 0.402042 -0.402042)
							(end 0.3302 -0.4318)
						)
					)
					(width 0)
					(fill yes)
				)
			)
		)
	)
	(footprint ""
		(layer "F.Cu")
		(at 145.106898 -179.683918 90)
		(property "Reference" "R499"
			(at 0 0 90)
			(layer "F.SilkS")
			(hide yes)
			(effects
				(font
					(size 1.27 1.27)
				)
			)
		)
		(property "Value" "2R6F-GP"
			(at -0.0508 -4.8514 90)
			(unlocked yes)
			(layer "F.Fab")
			(hide yes)
			(effects
				(font
					(size 1.016 1.016)
					(thickness 0.1524)
				)
			)
		)
		(property "Device Type" "R1206H26"
			(at 0 -6.3754 90)
			(unlocked yes)
			(layer "F.Fab")
			(hide yes)
			(effects
				(font
					(size 1.016 1.016)
					(thickness 0.1524)
				)
			)
		)
		(duplicate_pad_numbers_are_jumpers no)
		(fp_line
			(start 1.016 -2.2352)
			(end 1.016 2.2352)
			(stroke
				(width 0.1524)
				(type default)
			)
			(layer "F.SilkS")
		)
		(fp_line
			(start -1.016 -2.2352)
			(end 1.016 -2.2352)
			(stroke
				(width 0.1524)
				(type default)
			)
			(layer "F.SilkS")
		)
		(fp_line
			(start 1.016 2.2352)
			(end -1.016 2.2352)
			(stroke
				(width 0.1524)
				(type default)
			)
			(layer "F.SilkS")
		)
		(fp_line
			(start -1.016 2.2352)
			(end -1.016 -2.2352)
			(stroke
				(width 0.1524)
				(type default)
			)
			(layer "F.SilkS")
		)
		(fp_rect
			(start -1.0922 2.3114)
			(end 1.0922 -2.3114)
			(stroke
				(width 0)
				(type default)
			)
			(fill no)
			(layer "F.CrtYd")
		)
		(fp_poly
			(pts
				(xy -1.0922 -2.3114) (xy 1.0922 -2.3114) (xy 1.0922 2.3114) (xy -1.0922 2.3114)
			)
			(stroke
				(width 0)
				(type default)
			)
			(fill no)
			(layer "F.Fab")
		)
		(pad "1" smd rect
			(at 0 -1.397 90)
			(size 1.651 1.27)
			(layers "F.Cu" "F.Mask" "F.Paste")
			(net "P12V_HDD16")
		)
		(pad "2" smd rect
			(at 0 1.397 90)
			(size 1.651 1.27)
			(layers "F.Cu" "F.Mask" "F.Paste")
			(net "12V_PRE_16")
		)
	)
	(footprint ""
		(layer "F.Cu")
		(at 101.156516 -188.831982)
		(property "Reference" "Q230"
			(at 0 0 0)
			(layer "F.SilkS")
			(hide yes)
			(effects
				(font
					(size 1.27 1.27)
				)
			)
		)
		(property "Value" "2N7002K-2-GP"
			(at 0.127 -8.9662 0)
			(unlocked yes)
			(layer "F.Fab")
			(hide yes)
			(effects
				(font
					(size 1.016 1.016)
					(thickness 0.1524)
				)
			)
		)
		(property "Device Type" "SOT23DGS2D4H44"
			(at 0.127 -10.4902 0)
			(unlocked yes)
			(layer "F.Fab")
			(hide yes)
			(effects
				(font
					(size 1.016 1.016)
					(thickness 0.1524)
				)
			)
		)
		(duplicate_pad_numbers_are_jumpers no)
		(fp_line
			(start -1.651 -1.778)
			(end -1.651 1.778)
			(stroke
				(width 0.1524)
				(type default)
			)
			(layer "F.SilkS")
		)
		(fp_line
			(start -1.651 1.778)
			(end 1.651 1.778)
			(stroke
				(width 0.1524)
				(type default)
			)
			(layer "F.SilkS")
		)
		(fp_line
			(start 1.651 -1.778)
			(end -1.651 -1.778)
			(stroke
				(width 0.1524)
				(type default)
			)
			(layer "F.SilkS")
		)
		(fp_line
			(start 1.651 1.778)
			(end 1.651 -1.778)
			(stroke
				(width 0.1524)
				(type default)
			)
			(layer "F.SilkS")
		)
		(fp_poly
			(pts
				(xy -1.778 1.8796) (xy -1.778 -1.8796) (xy 1.778 -1.8796) (xy 1.778 1.8796)
			)
			(stroke
				(width 0)
				(type default)
			)
			(fill no)
			(layer "F.CrtYd")
		)
		(fp_poly
			(pts
				(xy -1.778 1.8796) (xy -1.778 -1.8796) (xy 1.778 -1.8796) (xy 1.778 1.8796)
			)
			(stroke
				(width 0)
				(type default)
			)
			(fill no)
			(layer "F.Fab")
		)
		(pad "D" smd custom
			(at 0 -0.9525)
			(size 0.1905 0.1905)
			(layers "F.Cu" "F.Mask" "F.Paste")
			(net "FLT_HDD3_N")
			(options
				(clearance outline)
				(anchor circle)
			)
			(primitives
				(gr_poly
					(pts
						(arc
							(start -0.1778 0.5715)
							(mid -0.321484 0.511984)
							(end -0.381 0.3683)
						)
						(arc
							(start -0.381 -0.3683)
							(mid -0.321484 -0.511984)
							(end -0.1778 -0.5715)
						)
						(arc
							(start 0.1778 -0.5715)
							(mid 0.321484 -0.511984)
							(end 0.381 -0.3683)
						)
						(arc
							(start 0.381 0.3683)
							(mid 0.321484 0.511984)
							(end 0.1778 0.5715)
						)
					)
					(width 0)
					(fill yes)
				)
			)
		)
		(pad "G" smd custom
			(at -0.98425 0.9525)
			(size 0.1905 0.1905)
			(layers "F.Cu" "F.Mask" "F.Paste")
			(net "DRIVE_A_3_FLT_LED")
			(options
				(clearance outline)
				(anchor circle)
			)
			(primitives
				(gr_poly
					(pts
						(arc
							(start -0.1778 0.5715)
							(mid -0.321484 0.511984)
							(end -0.381 0.3683)
						)
						(arc
							(start -0.381 -0.3683)
							(mid -0.321484 -0.511984)
							(end -0.1778 -0.5715)
						)
						(arc
							(start 0.1778 -0.5715)
							(mid 0.321484 -0.511984)
							(end 0.381 -0.3683)
						)
						(arc
							(start 0.381 0.3683)
							(mid 0.321484 0.511984)
							(end 0.1778 0.5715)
						)
					)
					(width 0)
					(fill yes)
				)
			)
		)
		(pad "S" smd custom
			(at 0.98425 0.9525)
			(size 0.1905 0.1905)
			(layers "F.Cu" "F.Mask" "F.Paste")
			(net "GND")
			(options
				(clearance outline)
				(anchor circle)
			)
			(primitives
				(gr_poly
					(pts
						(arc
							(start -0.1778 0.5715)
							(mid -0.321484 0.511984)
							(end -0.381 0.3683)
						)
						(arc
							(start -0.381 -0.3683)
							(mid -0.321484 -0.511984)
							(end -0.1778 -0.5715)
						)
						(arc
							(start 0.1778 -0.5715)
							(mid 0.321484 -0.511984)
							(end 0.381 -0.3683)
						)
						(arc
							(start 0.381 0.3683)
							(mid 0.321484 0.511984)
							(end 0.1778 0.5715)
						)
					)
					(width 0)
					(fill yes)
				)
			)
		)
	)
	(footprint ""
		(layer "F.Cu")
		(at 98.754184 -187.425584)
		(property "Reference" "R465"
			(at 0 0 0)
			(layer "F.SilkS")
			(hide yes)
			(effects
				(font
					(size 1.27 1.27)
				)
			)
		)
		(property "Value" "4K7R2J-2-GP"
			(at 0.064008 -3.993896 0)
			(unlocked yes)
			(layer "F.Fab")
			(hide yes)
			(effects
				(font
					(size 1.016 1.016)
					(thickness 0.1524)
				)
			)
		)
		(property "Device Type" "R402H16"
			(at 0.064008 -5.517896 0)
			(unlocked yes)
			(layer "F.Fab")
			(hide yes)
			(effects
				(font
					(size 1.016 1.016)
					(thickness 0.1524)
				)
			)
		)
		(duplicate_pad_numbers_are_jumpers no)
		(fp_line
			(start -0.508 -0.9398)
			(end -0.508 0.9398)
			(stroke
				(width 0.1524)
				(type default)
			)
			(layer "F.SilkS")
		)
		(fp_line
			(start 0.508 -0.9398)
			(end -0.508 -0.9398)
			(stroke
				(width 0.1524)
				(type default)
			)
			(layer "F.SilkS")
		)
		(fp_rect
			(start -0.508 0.9398)
			(end 0.508 -0.9398)
			(stroke
				(width 0)
				(type default)
			)
			(fill no)
			(layer "F.CrtYd")
		)
		(fp_rect
			(start -0.508 0.9398)
			(end 0.508 -0.9398)
			(stroke
				(width 0)
				(type default)
			)
			(fill no)
			(layer "F.Fab")
		)
		(pad "1" smd custom
			(at 0 -0.4445)
			(size 0.1397 0.1397)
			(layers "F.Cu" "F.Mask" "F.Paste")
			(net "DRIVE_A_3_FLT_LED")
			(options
				(clearance outline)
				(anchor circle)
			)
			(primitives
				(gr_poly
					(pts
						(arc
							(start -0.1778 -0.2794)
							(mid -0.249642 -0.249642)
							(end -0.2794 -0.1778)
						)
						(arc
							(start -0.2794 0.1778)
							(mid -0.249642 0.249642)
							(end -0.1778 0.2794)
						)
						(arc
							(start 0.1778 0.2794)
							(mid 0.249642 0.249642)
							(end 0.2794 0.1778)
						)
						(arc
							(start 0.2794 -0.1778)
							(mid 0.249642 -0.249642)
							(end 0.1778 -0.2794)
						)
					)
					(width 0)
					(fill yes)
				)
			)
		)
		(pad "2" smd custom
			(at 0 0.4445)
			(size 0.1397 0.1397)
			(layers "F.Cu" "F.Mask" "F.Paste")
			(net "GND")
			(options
				(clearance outline)
				(anchor circle)
			)
			(primitives
				(gr_poly
					(pts
						(arc
							(start -0.1778 -0.2794)
							(mid -0.249642 -0.249642)
							(end -0.2794 -0.1778)
						)
						(arc
							(start -0.2794 0.1778)
							(mid -0.249642 0.249642)
							(end -0.1778 0.2794)
						)
						(arc
							(start 0.1778 0.2794)
							(mid 0.249642 0.249642)
							(end 0.2794 0.1778)
						)
						(arc
							(start 0.2794 -0.1778)
							(mid 0.249642 -0.249642)
							(end 0.1778 -0.2794)
						)
					)
					(width 0)
					(fill yes)
				)
			)
		)
	)
	(footprint ""
		(layer "F.Cu")
		(at 27.178 -245.8466 90)
		(property "Reference" "C597"
			(at 0 0 90)
			(layer "F.SilkS")
			(hide yes)
			(effects
				(font
					(size 1.27 1.27)
				)
			)
		)
		(property "Value" "SC10U16V5KX-7-GP-U"
			(at -0.0762 -6.1214 90)
			(unlocked yes)
			(layer "F.Fab")
			(hide yes)
			(effects
				(font
					(size 1.016 1.016)
					(thickness 0.1524)
				)
			)
		)
		(property "Device Type" "C805H58"
			(at -0.0762 -8.1534 90)
			(unlocked yes)
			(layer "F.Fab")
			(hide yes)
			(effects
				(font
					(size 1.016 1.016)
					(thickness 0.1524)
				)
			)
		)
		(duplicate_pad_numbers_are_jumpers no)
		(fp_line
			(start 0.635 0)
			(end -0.635 0)
			(stroke
				(width 0.508)
				(type default)
			)
			(layer "F.SilkS")
		)
		(fp_rect
			(start -0.9652 1.778)
			(end 0.9652 -1.778)
			(stroke
				(width 0)
				(type default)
			)
			(fill no)
			(layer "F.CrtYd")
		)
		(fp_poly
			(pts
				(xy -0.9652 -1.778) (xy 0.9652 -1.778) (xy 0.9652 1.778) (xy -0.9652 1.778)
			)
			(stroke
				(width 0)
				(type default)
			)
			(fill no)
			(layer "F.Fab")
		)
		(pad "1" smd rect
			(at 0 -0.9652 90)
			(size 1.397 1.143)
			(layers "F.Cu" "F.Mask" "F.Paste")
			(net "P12V_A_VIN_U20")
		)
		(pad "2" smd rect
			(at 0 0.9652 90)
			(size 1.397 1.143)
			(layers "F.Cu" "F.Mask" "F.Paste")
			(net "GND")
		)
	)
	(footprint ""
		(layer "F.Cu")
		(at 406.164034 -245.335806 -90)
		(property "Reference" "R493"
			(at 0 0 270)
			(layer "F.SilkS")
			(hide yes)
			(effects
				(font
					(size 1.27 1.27)
				)
			)
		)
		(property "Value" "4K7R2J-2-GP"
			(at 0.064008 -3.993896 270)
			(unlocked yes)
			(layer "F.Fab")
			(hide yes)
			(effects
				(font
					(size 1.016 1.016)
					(thickness 0.1524)
				)
			)
		)
		(property "Device Type" "R402H16"
			(at 0.064008 -5.517896 270)
			(unlocked yes)
			(layer "F.Fab")
			(hide yes)
			(effects
				(font
					(size 1.016 1.016)
					(thickness 0.1524)
				)
			)
		)
		(duplicate_pad_numbers_are_jumpers no)
		(fp_line
			(start -0.508 -0.9398)
			(end -0.508 0.9398)
			(stroke
				(width 0.1524)
				(type default)
			)
			(layer "F.SilkS")
		)
		(fp_line
			(start 0.508 -0.9398)
			(end -0.508 -0.9398)
			(stroke
				(width 0.1524)
				(type default)
			)
			(layer "F.SilkS")
		)
		(fp_rect
			(start -0.508 0.9398)
			(end 0.508 -0.9398)
			(stroke
				(width 0)
				(type default)
			)
			(fill no)
			(layer "F.CrtYd")
		)
		(fp_rect
			(start -0.508 0.9398)
			(end 0.508 -0.9398)
			(stroke
				(width 0)
				(type default)
			)
			(fill no)
			(layer "F.Fab")
		)
		(pad "1" smd custom
			(at 0 -0.4445 270)
			(size 0.1397 0.1397)
			(layers "F.Cu" "F.Mask" "F.Paste")
			(net "DRIVE_A_9_FLT_LED")
			(options
				(clearance outline)
				(anchor circle)
			)
			(primitives
				(gr_poly
					(pts
						(arc
							(start -0.1778 -0.2794)
							(mid -0.249642 -0.249642)
							(end -0.2794 -0.1778)
						)
						(arc
							(start -0.2794 0.1778)
							(mid -0.249642 0.249642)
							(end -0.1778 0.2794)
						)
						(arc
							(start 0.1778 0.2794)
							(mid 0.249642 0.249642)
							(end 0.2794 0.1778)
						)
						(arc
							(start 0.2794 -0.1778)
							(mid 0.249642 -0.249642)
							(end 0.1778 -0.2794)
						)
					)
					(width 0)
					(fill yes)
				)
			)
		)
		(pad "2" smd custom
			(at 0 0.4445 270)
			(size 0.1397 0.1397)
			(layers "F.Cu" "F.Mask" "F.Paste")
			(net "GND")
			(options
				(clearance outline)
				(anchor circle)
			)
			(primitives
				(gr_poly
					(pts
						(arc
							(start -0.1778 -0.2794)
							(mid -0.249642 -0.249642)
							(end -0.2794 -0.1778)
						)
						(arc
							(start -0.2794 0.1778)
							(mid -0.249642 0.249642)
							(end -0.1778 0.2794)
						)
						(arc
							(start 0.1778 0.2794)
							(mid 0.249642 0.249642)
							(end 0.2794 0.1778)
						)
						(arc
							(start 0.2794 -0.1778)
							(mid 0.249642 -0.249642)
							(end 0.1778 -0.2794)
						)
					)
					(width 0)
					(fill yes)
				)
			)
		)
	)
	(footprint ""
		(layer "F.Cu")
		(at 380.98095 -180.064918 -90)
		(property "Reference" "R594"
			(at 0 0 270)
			(layer "F.SilkS")
			(hide yes)
			(effects
				(font
					(size 1.27 1.27)
				)
			)
		)
		(property "Value" "220R3F-1-GP"
			(at -0.0254 -2.5146 270)
			(unlocked yes)
			(layer "F.Fab")
			(hide yes)
			(effects
				(font
					(size 1.016 1.016)
					(thickness 0.1524)
				)
			)
		)
		(property "Device Type" "R603H22"
			(at -0.0254 -4.0386 270)
			(unlocked yes)
			(layer "F.Fab")
			(hide yes)
			(effects
				(font
					(size 1.016 1.016)
					(thickness 0.1524)
				)
			)
		)
		(duplicate_pad_numbers_are_jumpers no)
		(fp_line
			(start -0.4826 0)
			(end -0.2032 0)
			(stroke
				(width 0.2032)
				(type default)
			)
			(layer "F.SilkS")
		)
		(fp_line
			(start 0.2032 0)
			(end 0.4826 0)
			(stroke
				(width 0.2032)
				(type default)
			)
			(layer "F.SilkS")
		)
		(fp_rect
			(start -0.5842 1.3335)
			(end 0.5842 -1.3335)
			(stroke
				(width 0)
				(type default)
			)
			(fill no)
			(layer "F.CrtYd")
		)
		(fp_rect
			(start -0.5842 1.3335)
			(end 0.5842 -1.3335)
			(stroke
				(width 0)
				(type default)
			)
			(fill no)
			(layer "F.Fab")
		)
		(pad "1" smd custom
			(at 0 -0.762 270)
			(size 0.2159 0.2159)
			(layers "F.Cu" "F.Mask" "F.Paste")
			(net "HDD_PRSNT_20")
			(options
				(clearance outline)
				(anchor circle)
			)
			(primitives
				(gr_poly
					(pts
						(arc
							(start -0.3302 -0.4318)
							(mid -0.402042 -0.402042)
							(end -0.4318 -0.3302)
						)
						(arc
							(start -0.4318 0.3302)
							(mid -0.402042 0.402042)
							(end -0.3302 0.4318)
						)
						(arc
							(start 0.3302 0.4318)
							(mid 0.402042 0.402042)
							(end 0.4318 0.3302)
						)
						(arc
							(start 0.4318 -0.3302)
							(mid 0.402042 -0.402042)
							(end 0.3302 -0.4318)
						)
					)
					(width 0)
					(fill yes)
				)
			)
		)
		(pad "2" smd custom
			(at 0 0.762 270)
			(size 0.2159 0.2159)
			(layers "F.Cu" "F.Mask" "F.Paste")
			(net "DRIVE_A_20_INS")
			(options
				(clearance outline)
				(anchor circle)
			)
			(primitives
				(gr_poly
					(pts
						(arc
							(start -0.3302 -0.4318)
							(mid -0.402042 -0.402042)
							(end -0.4318 -0.3302)
						)
						(arc
							(start -0.4318 0.3302)
							(mid -0.402042 0.402042)
							(end -0.3302 0.4318)
						)
						(arc
							(start 0.3302 0.4318)
							(mid 0.402042 0.402042)
							(end 0.4318 0.3302)
						)
						(arc
							(start 0.4318 -0.3302)
							(mid 0.402042 -0.402042)
							(end 0.3302 -0.4318)
						)
					)
					(width 0)
					(fill yes)
				)
			)
		)
	)
)
